(kicad_pcb
	(version 20241229)
	(generator "pcbnew")
	(generator_version "9.0")
	(general
		(thickness 1.294)
		(legacy_teardrops no)
	)
	(paper "A3")
	(title_block
		(title "Kintex 410T devboard")
		(date "2024-04-03")
		(rev "1.1.2")
		(comment 9 "footprint 170 of 975 (U1), pads 123-181 of 900")
	)
	(layers
		(0 "F.Cu" mixed)
		(4 "In1.Cu" power)
		(6 "In2.Cu" power)
		(8 "In3.Cu" mixed)
		(10 "In4.Cu" power)
		(12 "In5.Cu" mixed)
		(14 "In6.Cu" power)
		(16 "In7.Cu" mixed)
		(18 "In8.Cu" power)
		(2 "B.Cu" mixed)
		(9 "F.Adhes" user "F.Adhesive")
		(11 "B.Adhes" user "B.Adhesive")
		(13 "F.Paste" user)
		(15 "B.Paste" user)
		(5 "F.SilkS" user "F.Silkscreen")
		(7 "B.SilkS" user "B.Silkscreen")
		(1 "F.Mask" user)
		(3 "B.Mask" user)
		(17 "Dwgs.User" user "User.Drawings")
		(19 "Cmts.User" user "User.Comments")
		(21 "Eco1.User" user "User.Eco1")
		(23 "Eco2.User" user "User.Eco2")
		(25 "Edge.Cuts" user)
		(27 "Margin" user)
		(31 "F.CrtYd" user "F.Courtyard")
		(29 "B.CrtYd" user "B.Courtyard")
		(35 "F.Fab" user)
		(33 "B.Fab" user)
	)
	(footprint "antmicro-footprints:BGA-900_31x31mm_Layout30x30_P1x1mm_FFG900"
		(locked yes)
		(layer "F.Cu")
		(at 200 130)
		(property "Reference" "U1"
			(at -15.74 -15.78 0)
			(layer "F.SilkS")
			(effects
				(font
					(size 0.7 0.7)
					(thickness 0.15)
				)
				(justify left bottom)
			)
		)
		(property "Value" "XC7K410T-2FFG900I"
			(at -4.436 17.635 0)
			(layer "F.Fab")
			(effects
				(font
					(size 0.7 0.7)
					(thickness 0.15)
				)
				(justify left bottom)
			)
		)
		(property "Description" "FPGA, Kintex-7, MMCM, PLL, 350 I/O's, 710 MHz, 406720 Cells, 970 mV to 1.03 V, FCBGA-900"
			(at 0 0 0)
			(layer "F.Fab")
			(hide yes)
			(effects
				(font
					(size 1.27 1.27)
					(thickness 0.15)
				)
			)
		)
		(property "Author" "Antmicro"
			(at 0 0 0)
			(layer "F.Fab")
			(hide yes)
			(effects
				(font
					(size 1 1)
					(thickness 0.15)
				)
			)
		)
		(property "License" "Apache-2.0"
			(at 0 0 0)
			(layer "F.Fab")
			(hide yes)
			(effects
				(font
					(size 1 1)
					(thickness 0.15)
				)
			)
		)
		(property "MPN" "XC7K410T-2FFG900I"
			(at 0 0 0)
			(layer "F.Fab")
			(hide yes)
			(effects
				(font
					(size 1 1)
					(thickness 0.15)
				)
			)
		)
		(property "Manufacturer" "AMD-Xilinx"
			(at 0 0 0)
			(layer "F.Fab")
			(hide yes)
			(effects
				(font
					(size 1 1)
					(thickness 0.15)
				)
			)
		)
		(sheetname "FPGA supply")
		(sheetfile "fpga-supply.kicad_sch")
		(attr smd)
		(pad "AD3" smd circle
			(at -12.5 8.5)
			(size 0.5 0.5)
			(property pad_prop_bga)
			(layers "F.Cu" "F.Mask" "F.Paste")
			(net 545 "/DRAM + SRAM/DDR.A14")
			(pinfunction "IO_L1N_T0_34")
			(pintype "bidirectional")
			(die_length 19.656)
			(solder_mask_margin 0.02)
		)
		(pad "AD4" smd circle
			(at -11.5 8.5)
			(size 0.5 0.5)
			(property pad_prop_bga)
			(layers "F.Cu" "F.Mask" "F.Paste")
			(net 546 "/DRAM + SRAM/DDR.A15")
			(pinfunction "IO_L1P_T0_34")
			(pintype "bidirectional")
			(die_length 20.951)
			(solder_mask_margin 0.02)
		)
		(pad "AD5" smd circle
			(at -10.5 8.5)
			(size 0.5 0.5)
			(property pad_prop_bga)
			(layers "F.Cu" "F.Mask" "F.Paste")
			(net 1 "GND")
			(pinfunction "GND")
			(pintype "passive")
			(solder_mask_margin 0.02)
		)
		(pad "AD6" smd circle
			(at -9.5 8.5)
			(size 0.5 0.5)
			(property pad_prop_bga)
			(layers "F.Cu" "F.Mask" "F.Paste")
			(net 540 "/DRAM + SRAM/DDR.A9")
			(pinfunction "IO_L5P_T0_34")
			(pintype "bidirectional")
			(die_length 19.148)
			(solder_mask_margin 0.02)
		)
		(pad "AD7" smd circle
			(at -8.5 8.5)
			(size 0.5 0.5)
			(property pad_prop_bga)
			(layers "F.Cu" "F.Mask" "F.Paste")
			(net 11 "+0V675_VREF")
			(pinfunction "IO_L6N_T0_VREF_34")
			(pintype "bidirectional")
			(die_length 15.552)
			(solder_mask_margin 0.02)
		)
		(pad "AD8" smd circle
			(at -7.5 8.5)
			(size 0.5 0.5)
			(property pad_prop_bga)
			(layers "F.Cu" "F.Mask" "F.Paste")
			(net 412 "unconnected-(U1E-IO_L8P_T1_33-PadAD8)")
			(pinfunction "IO_L8P_T1_33")
			(pintype "bidirectional+no_connect")
			(die_length 14.02)
			(solder_mask_margin 0.02)
		)
		(pad "AD9" smd circle
			(at -6.5 8.5)
			(size 0.5 0.5)
			(property pad_prop_bga)
			(layers "F.Cu" "F.Mask" "F.Paste")
			(net 640 "/Clocks/LVDS_XO_200M_ENA")
			(pinfunction "IO_L10P_T1_33")
			(pintype "bidirectional")
			(die_length 15.484)
			(solder_mask_margin 0.02)
		)
		(pad "AD10" smd circle
			(at -5.5 8.5)
			(size 0.5 0.5)
			(property pad_prop_bga)
			(layers "F.Cu" "F.Mask" "F.Paste")
			(net 26 "+1V8")
			(pinfunction "VCCO_33")
			(pintype "passive")
			(solder_mask_margin 0.02)
		)
		(pad "AD11" smd circle
			(at -4.5 8.5)
			(size 0.5 0.5)
			(property pad_prop_bga)
			(layers "F.Cu" "F.Mask" "F.Paste")
			(net 623 "/Clocks/SYS.CLK_N")
			(pinfunction "IO_L12N_T1_MRCC_33")
			(pintype "bidirectional")
			(die_length 17.198)
			(solder_mask_margin 0.02)
		)
		(pad "AD12" smd circle
			(at -3.5 8.5)
			(size 0.5 0.5)
			(property pad_prop_bga)
			(layers "F.Cu" "F.Mask" "F.Paste")
			(net 624 "/Clocks/SYS.CLK_P")
			(pinfunction "IO_L12P_T1_MRCC_33")
			(pintype "bidirectional")
			(die_length 17.066)
			(solder_mask_margin 0.02)
		)
		(pad "AD13" smd circle
			(at -2.5 8.5)
			(size 0.5 0.5)
			(property pad_prop_bga)
			(layers "F.Cu" "F.Mask" "F.Paste")
			(net 415 "unconnected-(U1E-IO_25_VRP_33-PadAD13)")
			(pinfunction "IO_25_VRP_33")
			(pintype "bidirectional+no_connect")
			(die_length 15.655)
			(solder_mask_margin 0.02)
		)
		(pad "AD14" smd circle
			(at -1.5 8.5)
			(size 0.5 0.5)
			(property pad_prop_bga)
			(layers "F.Cu" "F.Mask" "F.Paste")
			(net 515 "/FPGA Bank 18 & 32/ETH_RMII.TXD1")
			(pinfunction "IO_L22N_T3_32")
			(pintype "bidirectional")
			(die_length 12.008)
			(solder_mask_margin 0.02)
		)
		(pad "AD15" smd circle
			(at -0.5 8.5)
			(size 0.5 0.5)
			(property pad_prop_bga)
			(layers "F.Cu" "F.Mask" "F.Paste")
			(net 1 "GND")
			(pinfunction "GND")
			(pintype "passive")
			(solder_mask_margin 0.02)
		)
		(pad "AD16" smd circle
			(at 0.5 8.5)
			(size 0.5 0.5)
			(property pad_prop_bga)
			(layers "F.Cu" "F.Mask" "F.Paste")
			(net 605 "unconnected-(U1D-IO_L14N_T2_SRCC_32-PadAD16)")
			(pinfunction "IO_L14N_T2_SRCC_32")
			(pintype "bidirectional+no_connect")
			(die_length 20.892)
			(solder_mask_margin 0.02)
		)
		(pad "AD17" smd circle
			(at 1.5 8.5)
			(size 0.5 0.5)
			(property pad_prop_bga)
			(layers "F.Cu" "F.Mask" "F.Paste")
			(net 606 "unconnected-(U1D-IO_L14P_T2_SRCC_32-PadAD17)")
			(pinfunction "IO_L14P_T2_SRCC_32")
			(pintype "bidirectional+no_connect")
			(die_length 20.478)
			(solder_mask_margin 0.02)
		)
		(pad "AD18" smd circle
			(at 2.5 8.5)
			(size 0.5 0.5)
			(property pad_prop_bga)
			(layers "F.Cu" "F.Mask" "F.Paste")
			(net 501 "/FPGA Bank 18 & 32/ETH_RMII.~{RESET}")
			(pinfunction "IO_L13P_T2_MRCC_32")
			(pintype "bidirectional")
			(die_length 22.172)
			(solder_mask_margin 0.02)
		)
		(pad "AD19" smd circle
			(at 3.5 8.5)
			(size 0.5 0.5)
			(property pad_prop_bga)
			(layers "F.Cu" "F.Mask" "F.Paste")
			(net 607 "unconnected-(U1D-IO_L10P_T1_32-PadAD19)")
			(pinfunction "IO_L10P_T1_32")
			(pintype "bidirectional+no_connect")
			(die_length 21.412)
			(solder_mask_margin 0.02)
		)
		(pad "AD20" smd circle
			(at 4.5 8.5)
			(size 0.5 0.5)
			(property pad_prop_bga)
			(layers "F.Cu" "F.Mask" "F.Paste")
			(net 24 "+3V3")
			(pinfunction "VCCO_12")
			(pintype "passive")
			(solder_mask_margin 0.02)
		)
		(pad "AD21" smd circle
			(at 5.5 8.5)
			(size 0.5 0.5)
			(property pad_prop_bga)
			(layers "F.Cu" "F.Mask" "F.Paste")
			(net 1392 "/SUP_MCU.ALE")
			(pinfunction "IO_L10P_T1_12")
			(pintype "bidirectional")
			(die_length 9.418)
			(solder_mask_margin 0.02)
		)
		(pad "AD22" smd circle
			(at 6.5 8.5)
			(size 0.5 0.5)
			(property pad_prop_bga)
			(layers "F.Cu" "F.Mask" "F.Paste")
			(net 1328 "/SUP_MCU.TX1")
			(pinfunction "IO_L8N_T1_12")
			(pintype "bidirectional")
			(die_length 8.457)
			(solder_mask_margin 0.02)
		)
		(pad "AD23" smd circle
			(at 7.5 8.5)
			(size 0.5 0.5)
			(property pad_prop_bga)
			(layers "F.Cu" "F.Mask" "F.Paste")
			(net 1365 "/SUP_MCU.CLKO")
			(pinfunction "IO_L12P_T1_MRCC_12")
			(pintype "bidirectional")
			(die_length 9.583)
			(solder_mask_margin 0.02)
		)
		(pad "AD24" smd circle
			(at 8.5 8.5)
			(size 0.5 0.5)
			(property pad_prop_bga)
			(layers "F.Cu" "F.Mask" "F.Paste")
			(net 1351 "/SUP_MCU.A0")
			(pinfunction "IO_L9N_T1_DQS_12")
			(pintype "bidirectional")
			(die_length 9.257)
			(solder_mask_margin 0.02)
		)
		(pad "AD25" smd circle
			(at 9.5 8.5)
			(size 0.5 0.5)
			(property pad_prop_bga)
			(layers "F.Cu" "F.Mask" "F.Paste")
			(net 1 "GND")
			(pinfunction "GND")
			(pintype "passive")
			(solder_mask_margin 0.02)
		)
		(pad "AD26" smd circle
			(at 10.5 8.5)
			(size 0.5 0.5)
			(property pad_prop_bga)
			(layers "F.Cu" "F.Mask" "F.Paste")
			(net 608 "unconnected-(U1A-IO_L19N_T3_VREF_13-PadAD26)")
			(pinfunction "IO_L19N_T3_VREF_13")
			(pintype "bidirectional+no_connect")
			(die_length 16.018)
			(solder_mask_margin 0.02)
		)
		(pad "AD27" smd circle
			(at 11.5 8.5)
			(size 0.5 0.5)
			(property pad_prop_bga)
			(layers "F.Cu" "F.Mask" "F.Paste")
			(net 438 "/FPGA Bank 12 & 13/PMOD_A.IO9")
			(pinfunction "IO_L11P_T1_SRCC_13")
			(pintype "bidirectional")
			(die_length 15.78)
			(solder_mask_margin 0.02)
		)
		(pad "AD28" smd circle
			(at 12.5 8.5)
			(size 0.5 0.5)
			(property pad_prop_bga)
			(layers "F.Cu" "F.Mask" "F.Paste")
			(net 442 "/FPGA Bank 12 & 13/PMOD_B.IO7")
			(pinfunction "IO_L11N_T1_SRCC_13")
			(pintype "bidirectional")
			(die_length 16.608)
			(solder_mask_margin 0.02)
		)
		(pad "AD29" smd circle
			(at 13.5 8.5)
			(size 0.5 0.5)
			(property pad_prop_bga)
			(layers "F.Cu" "F.Mask" "F.Paste")
			(net 570 "/FPGA Bank 12 & 13/USB_USER.VBUS_PEN")
			(pinfunction "IO_L9P_T1_DQS_13")
			(pintype "bidirectional")
			(die_length 18.051)
			(solder_mask_margin 0.02)
		)
		(pad "AD30" smd circle
			(at 14.5 8.5)
			(size 0.5 0.5)
			(property pad_prop_bga)
			(layers "F.Cu" "F.Mask" "F.Paste")
			(net 24 "+3V3")
			(pinfunction "VCCO_13")
			(pintype "passive")
			(solder_mask_margin 0.02)
		)
		(pad "AE1" smd circle
			(at -14.5 9.5)
			(size 0.5 0.5)
			(property pad_prop_bga)
			(layers "F.Cu" "F.Mask" "F.Paste")
			(net 535 "/DRAM + SRAM/DDR.A4")
			(pinfunction "IO_L8P_T1_34")
			(pintype "bidirectional")
			(die_length 19.484)
			(solder_mask_margin 0.02)
		)
		(pad "AE2" smd circle
			(at -13.5 9.5)
			(size 0.5 0.5)
			(property pad_prop_bga)
			(layers "F.Cu" "F.Mask" "F.Paste")
			(net 1 "GND")
			(pinfunction "GND")
			(pintype "passive")
			(solder_mask_margin 0.02)
		)
		(pad "AE3" smd circle
			(at -12.5 9.5)
			(size 0.5 0.5)
			(property pad_prop_bga)
			(layers "F.Cu" "F.Mask" "F.Paste")
			(net 549 "/DRAM + SRAM/DDR.BA2")
			(pinfunction "IO_L10N_T1_34")
			(pintype "bidirectional")
			(die_length 20.774)
			(solder_mask_margin 0.02)
		)
		(pad "AE4" smd circle
			(at -11.5 9.5)
			(size 0.5 0.5)
			(property pad_prop_bga)
			(layers "F.Cu" "F.Mask" "F.Paste")
			(net 531 "/DRAM + SRAM/DDR.A0")
			(pinfunction "IO_L10P_T1_34")
			(pintype "bidirectional")
			(die_length 20.074)
			(solder_mask_margin 0.02)
		)
		(pad "AE5" smd circle
			(at -10.5 9.5)
			(size 0.5 0.5)
			(property pad_prop_bga)
			(layers "F.Cu" "F.Mask" "F.Paste")
			(net 548 "/DRAM + SRAM/DDR.BA1")
			(pinfunction "IO_L11P_T1_SRCC_34")
			(pintype "bidirectional")
			(die_length 21.14)
			(solder_mask_margin 0.02)
		)
		(pad "AE6" smd circle
			(at -9.5 9.5)
			(size 0.5 0.5)
			(property pad_prop_bga)
			(layers "F.Cu" "F.Mask" "F.Paste")
			(net 539 "/DRAM + SRAM/DDR.A8")
			(pinfunction "IO_L5N_T0_34")
			(pintype "bidirectional")
			(die_length 19.788)
			(solder_mask_margin 0.02)
		)
		(pad "AE7" smd circle
			(at -8.5 9.5)
			(size 0.5 0.5)
			(property pad_prop_bga)
			(layers "F.Cu" "F.Mask" "F.Paste")
			(net 25 "+1V35")
			(pinfunction "VCCO_34")
			(pintype "passive")
			(solder_mask_margin 0.02)
		)
		(pad "AE8" smd circle
			(at -7.5 9.5)
			(size 0.5 0.5)
			(property pad_prop_bga)
			(layers "F.Cu" "F.Mask" "F.Paste")
			(net 421 "unconnected-(U1E-IO_L8N_T1_33-PadAE8)")
			(pinfunction "IO_L8N_T1_33")
			(pintype "bidirectional+no_connect")
			(die_length 15.592)
			(solder_mask_margin 0.02)
		)
		(pad "AE9" smd circle
			(at -6.5 9.5)
			(size 0.5 0.5)
			(property pad_prop_bga)
			(layers "F.Cu" "F.Mask" "F.Paste")
			(net 390 "/FPGA Bank 33 & 34/SD_CARD.DAT2")
			(pinfunction "IO_L10N_T1_33")
			(pintype "bidirectional")
			(die_length 16.427)
			(solder_mask_margin 0.02)
		)
		(pad "AE10" smd circle
			(at -5.5 9.5)
			(size 0.5 0.5)
			(property pad_prop_bga)
			(layers "F.Cu" "F.Mask" "F.Paste")
			(net 422 "unconnected-(U1E-IO_L14P_T2_SRCC_33-PadAE10)")
			(pinfunction "IO_L14P_T2_SRCC_33")
			(pintype "bidirectional+no_connect")
			(die_length 15.465)
			(solder_mask_margin 0.02)
		)
		(pad "AE11" smd circle
			(at -4.5 9.5)
			(size 0.5 0.5)
			(property pad_prop_bga)
			(layers "F.Cu" "F.Mask" "F.Paste")
			(net 425 "unconnected-(U1E-IO_L11P_T1_SRCC_33-PadAE11)")
			(pinfunction "IO_L11P_T1_SRCC_33")
			(pintype "bidirectional+no_connect")
			(die_length 18.396)
			(solder_mask_margin 0.02)
		)
		(pad "AE12" smd circle
			(at -3.5 9.5)
			(size 0.5 0.5)
			(property pad_prop_bga)
			(layers "F.Cu" "F.Mask" "F.Paste")
			(net 1 "GND")
			(pinfunction "GND")
			(pintype "passive")
			(solder_mask_margin 0.02)
		)
		(pad "AE13" smd circle
			(at -2.5 9.5)
			(size 0.5 0.5)
			(property pad_prop_bga)
			(layers "F.Cu" "F.Mask" "F.Paste")
			(net 416 "/FPGA Bank 33 & 34/SD_CARD.~{CD}")
			(pinfunction "IO_L19P_T3_33")
			(pintype "bidirectional")
			(die_length 19.974)
			(solder_mask_margin 0.02)
		)
		(pad "AE14" smd circle
			(at -1.5 9.5)
			(size 0.5 0.5)
			(property pad_prop_bga)
			(layers "F.Cu" "F.Mask" "F.Paste")
			(net 609 "unconnected-(U1D-IO_L19N_T3_VREF_32-PadAE14)")
			(pinfunction "IO_L19N_T3_VREF_32")
			(pintype "bidirectional+no_connect")
			(die_length 11.352)
			(solder_mask_margin 0.02)
		)
		(pad "AE15" smd circle
			(at -0.5 9.5)
			(size 0.5 0.5)
			(property pad_prop_bga)
			(layers "F.Cu" "F.Mask" "F.Paste")
			(net 610 "unconnected-(U1D-IO_L19P_T3_32-PadAE15)")
			(pinfunction "IO_L19P_T3_32")
			(pintype "bidirectional+no_connect")
			(die_length 14.144)
			(solder_mask_margin 0.02)
		)
		(pad "AE16" smd circle
			(at 0.5 9.5)
			(size 0.5 0.5)
			(property pad_prop_bga)
			(layers "F.Cu" "F.Mask" "F.Paste")
			(net 611 "unconnected-(U1D-IO_L6P_T0_32-PadAE16)")
			(pinfunction "IO_L6P_T0_32")
			(pintype "bidirectional+no_connect")
			(die_length 19.283)
			(solder_mask_margin 0.02)
		)
		(pad "AE17" smd circle
			(at 1.5 9.5)
			(size 0.5 0.5)
			(property pad_prop_bga)
			(layers "F.Cu" "F.Mask" "F.Paste")
			(net 26 "+1V8")
			(pinfunction "VCCO_32")
			(pintype "passive")
			(solder_mask_margin 0.02)
		)
		(pad "AE18" smd circle
			(at 2.5 9.5)
			(size 0.5 0.5)
			(property pad_prop_bga)
			(layers "F.Cu" "F.Mask" "F.Paste")
			(net 520 "/FPGA Bank 18 & 32/ETH_RMII.RXD1")
			(pinfunction "IO_L13N_T2_MRCC_32")
			(pintype "bidirectional")
			(die_length 22.208)
			(solder_mask_margin 0.02)
		)
		(pad "AE19" smd circle
			(at 3.5 9.5)
			(size 0.5 0.5)
			(property pad_prop_bga)
			(layers "F.Cu" "F.Mask" "F.Paste")
			(net 612 "unconnected-(U1D-IO_L10N_T1_32-PadAE19)")
			(pinfunction "IO_L10N_T1_32")
			(pintype "bidirectional+no_connect")
			(die_length 22.544)
			(solder_mask_margin 0.02)
		)
		(pad "AE20" smd circle
			(at 4.5 9.5)
			(size 0.5 0.5)
			(property pad_prop_bga)
			(layers "F.Cu" "F.Mask" "F.Paste")
			(net 474 "/FPGA Bank 12 & 13/CW_HEADER.RST")
			(pinfunction "IO_25_12")
			(pintype "bidirectional")
			(die_length 6.449)
			(solder_mask_margin 0.02)
		)
		(pad "AE21" smd circle
			(at 5.5 9.5)
			(size 0.5 0.5)
			(property pad_prop_bga)
			(layers "F.Cu" "F.Mask" "F.Paste")
			(net 1375 "/SUP_MCU.D7")
			(pinfunction "IO_L10N_T1_12")
			(pintype "bidirectional")
			(die_length 10.51)
			(solder_mask_margin 0.02)
		)
		(pad "AE22" smd circle
			(at 6.5 9.5)
			(size 0.5 0.5)
			(property pad_prop_bga)
			(layers "F.Cu" "F.Mask" "F.Paste")
			(net 1 "GND")
			(pinfunction "GND")
			(pintype "passive")
			(solder_mask_margin 0.02)
		)
		(pad "AE23" smd circle
			(at 7.5 9.5)
			(size 0.5 0.5)
			(property pad_prop_bga)
			(layers "F.Cu" "F.Mask" "F.Paste")
			(net 1376 "/SUP_MCU.CE")
			(pinfunction "IO_L11P_T1_SRCC_12")
			(pintype "bidirectional")
			(die_length 10.622)
			(solder_mask_margin 0.02)
		)
		(pad "AE24" smd circle
			(at 8.5 9.5)
			(size 0.5 0.5)
			(property pad_prop_bga)
			(layers "F.Cu" "F.Mask" "F.Paste")
			(net 1329 "/SUP_MCU.TX0")
			(pinfunction "IO_L12N_T1_MRCC_12")
			(pintype "bidirectional")
			(die_length 9.679)
			(solder_mask_margin 0.02)
		)
		(pad "AE25" smd circle
			(at 9.5 9.5)
			(size 0.5 0.5)
			(property pad_prop_bga)
			(layers "F.Cu" "F.Mask" "F.Paste")
			(net 1354 "/SUP_MCU.A7")
			(pinfunction "IO_L16P_T2_12")
			(pintype "bidirectional")
			(die_length 16.226)
			(solder_mask_margin 0.02)
		)
		(pad "AE26" smd circle
			(at 10.5 9.5)
			(size 0.5 0.5)
			(property pad_prop_bga)
			(layers "F.Cu" "F.Mask" "F.Paste")
			(net 432 "/FPGA Bank 12 & 13/FAN_PWM_CTRL")
			(pinfunction "IO_25_13")
			(pintype "bidirectional")
			(die_length 12.263)
			(solder_mask_margin 0.02)
		)
		(pad "AE27" smd circle
			(at 11.5 9.5)
			(size 0.5 0.5)
			(property pad_prop_bga)
			(layers "F.Cu" "F.Mask" "F.Paste")
			(net 24 "+3V3")
			(pinfunction "VCCO_13")
			(pintype "passive")
			(solder_mask_margin 0.02)
		)
		(pad "AE28" smd circle
			(at 12.5 9.5)
			(size 0.5 0.5)
			(property pad_prop_bga)
			(layers "F.Cu" "F.Mask" "F.Paste")
			(net 1403 "/PLL.CLK1")
			(pinfunction "IO_L14P_T2_SRCC_13")
			(pintype "bidirectional")
			(die_length 19.231)
			(solder_mask_margin 0.02)
		)
		(pad "AE29" smd circle
			(at 13.5 9.5)
			(size 0.5 0.5)
			(property pad_prop_bga)
			(layers "F.Cu" "F.Mask" "F.Paste")
			(net 613 "unconnected-(U1A-IO_L9N_T1_DQS_13-PadAE29)")
			(pinfunction "IO_L9N_T1_DQS_13")
			(pintype "bidirectional+no_connect")
			(die_length 18.383)
			(solder_mask_margin 0.02)
		)
		(pad "AE30" smd circle
			(at 14.5 9.5)
			(size 0.5 0.5)
			(property pad_prop_bga)
			(layers "F.Cu" "F.Mask" "F.Paste")
			(net 614 "unconnected-(U1A-IO_L16P_T2_13-PadAE30)")
			(pinfunction "IO_L16P_T2_13")
			(pintype "bidirectional+no_connect")
			(die_length 20.537)
			(solder_mask_margin 0.02)
		)
		(pad "AF1" smd circle
			(at -14.5 10.5)
			(size 0.5 0.5)
			(property pad_prop_bga)
			(layers "F.Cu" "F.Mask" "F.Paste")
			(net 534 "/DRAM + SRAM/DDR.A3")
			(pinfunction "IO_L8N_T1_34")
			(pintype "bidirectional")
			(die_length 20.617)
			(solder_mask_margin 0.02)
		)
	)
)
